# S9S_MB_2U (Grand Teton) — schematic parts with pin connectivity, parts 1597–1597 of 6093; source: Cadence DE-HDL packaged netlist (pstxprt.dat, pstxnet.dat, pstchip.dat)

J4  SCONN288_ADR50017P087CC  SCONN288_ADR50017-P087CC IO  pkg DDR288S_1-1VXB  page 85
  1  VIN_BULK0  POWER  = P12V_S3_AUX_CPU0_NVDIMM
  2  RFU0  TRI  = TP_CHB_CPU0_DIMM2_FRU_0
  3  VIN_MGMT  POWER  = P3V3_AUX
  4  HSCL  IN  = I3C_SPD_DDRABCD_CPU0_LVC1_SCL_3
  5  HSDA  BI  = I3C_SPD_DDRABCD_CPU0_LVC1_SDA
  6  VSS0  POWER  = GND
  7  DQ0_A  BI  = M_B_CPU0_SA_DQ<0>
  8  VSS1  POWER  = GND
  9  DQ1_A  BI  = M_B_CPU0_SA_DQ<1>
  10  VSS2  POWER  = GND
  11  DQS0_A_T  BI  = M_B_CPU0_SA_DQS_DP<0>
  12  DQS0_A_C  BI  = M_B_CPU0_SA_DQS_DN<0>
  13  VSS3  POWER  = GND
  14  DQ4_A  BI  = M_B_CPU0_SA_DQ<4>
  15  VSS4  POWER  = GND
  16  DQ5_A  BI  = M_B_CPU0_SA_DQ<5>
  17  VSS5  POWER  = GND
  18  DQ8_A  BI  = M_B_CPU0_SA_DQ<8>
  19  VSS6  POWER  = GND
  20  DQ9_A  BI  = M_B_CPU0_SA_DQ<9>
  21  VSS7  POWER  = GND
  22  DQS1_A_T  BI  = M_B_CPU0_SA_DQS_DP<1>
  23  DQS1_A_C  BI  = M_B_CPU0_SA_DQS_DN<1>
  24  VSS8  POWER  = GND
  25  DQ12_A  BI  = M_B_CPU0_SA_DQ<12>
  26  VSS9  POWER  = GND
  27  DQ13_A  BI  = M_B_CPU0_SA_DQ<13>
  28  VSS10  POWER  = GND
  29  DQ16_A  BI  = M_B_CPU0_SA_DQ<16>
  30  VSS11  POWER  = GND
  31  DQ17_A  BI  = M_B_CPU0_SA_DQ<17>
  32  VSS12  POWER  = GND
  33  DQS2_A_T  BI  = M_B_CPU0_SA_DQS_DP<2>
  34  DQS2_A_C  BI  = M_B_CPU0_SA_DQS_DN<2>
  35  VSS13  POWER  = GND
  36  DQ20_A  BI  = M_B_CPU0_SA_DQ<20>
  37  VSS14  POWER  = GND
  38  DQ21_A  BI  = M_B_CPU0_SA_DQ<21>
  39  VSS15  POWER  = GND
  40  DQ24_A  BI  = M_B_CPU0_SA_DQ<24>
  41  VSS16  POWER  = GND
  42  DQ25_A  BI  = M_B_CPU0_SA_DQ<25>
  43  VSS17  POWER  = GND
  44  DQS3_A_T  BI  = M_B_CPU0_SA_DQS_DP<3>
  45  DQS3_A_C  BI  = M_B_CPU0_SA_DQS_DN<3>
  46  VSS18  POWER  = GND
  47  DQ28_A  BI  = M_B_CPU0_SA_DQ<28>
  48  VSS19  POWER  = GND
  49  DQ29_A  BI  = M_B_CPU0_SA_DQ<29>
  50  VSS20  POWER  = GND
  51  CB0_A  BI  = M_B_CPU0_SA_CB<0>
  52  VSS21  POWER  = GND
  53  CB1_A  BI  = M_B_CPU0_SA_CB<1>
  54  VSS22  POWER  = GND
  55  DQS4_A_T  BI  = M_B_CPU0_SA_DQS_DP<4>
  56  DQS4_A_C  BI  = M_B_CPU0_SA_DQS_DN<4>
  57  VSS23  POWER  = GND
  58  CB4_A  BI  = M_B_CPU0_SA_CB<4>
  59  VSS24  POWER  = GND
  60  CB5_A  BI  = M_B_CPU0_SA_CB<5>
  61  VSS25  POWER  = GND
  62  ALERT_N  OUT  = M_B_CPU0_ALERT_N
  63  VSS26  POWER  = GND
  64  CS0_A_N  IN  = M_B_CPU0_SA_CS_N<2>
  65  VSS27  POWER  = GND
  66  CA0_A  IN  = M_B_CPU0_SA_CA<0>
  67  VSS28  POWER  = GND
  68  CA2_A  IN  = M_B_CPU0_SA_CA<2>
  69  VSS29  POWER  = GND
  70  CA4_A  IN  = M_B_CPU0_SA_CA<4>
  71  VSS30  POWER  = GND
  72  CA6_A  IN  = M_B_CPU0_SA_CA<6>
  73  VSS31  POWER  = GND
  74  PAR_A  IN  = M_B_CPU0_SA_PAR
  75  VSS32  POWER  = GND
  76  CA0_B  IN  = M_B_CPU0_SB_CA<0>
  77  VSS33  POWER  = GND
  78  CA2_B  IN  = M_B_CPU0_SB_CA<2>
  79  VSS34  POWER  = GND
  80  CA4_B  IN  = M_B_CPU0_SB_CA<4>
  81  VSS35  POWER  = GND
  82  CA6_B  IN  = M_B_CPU0_SB_CA<6>
  83  VSS36  POWER  = GND
  84  CS0_B_N  IN  = M_B_CPU0_SB_CS_N<2>
  85  VSS37  POWER  = GND
  86  \lbd||rsp_a_n\  OUT  = M_B_CPU0_SA_RSP<1>
  87  \lbs||rsp_b_n\  OUT  = M_B_CPU0_SB_RSP<1>
  88  VSS38  POWER  = GND
  89  CB4_B  BI  = M_B_CPU0_SB_CB<4>
  90  VSS39  POWER  = GND
  91  CB5_B  BI  = M_B_CPU0_SB_CB<5>
  92  VSS40  POWER  = GND
  93  \dqs9_b_t||tdqs9_b_t||dbi4_b_n\  BI  = M_B_CPU0_SB_DQS_DP<9>
  94  \dqs9_b_c||tdqs9_b_c\  BI  = M_B_CPU0_SB_DQS_DN<9>
  95  VSS41  POWER  = GND
  96  CB0_B  BI  = M_B_CPU0_SB_CB<0>
  97  VSS42  POWER  = GND
  98  CB1_B  BI  = M_B_CPU0_SB_CB<1>
  99  VSS43  POWER  = GND
  100  DQ0_B  BI  = M_B_CPU0_SB_DQ<0>
  101  VSS44  POWER  = GND
  102  DQ1_B  BI  = M_B_CPU0_SB_DQ<1>
  103  VSS45  POWER  = GND
  104  DQS0_B_T  BI  = M_B_CPU0_SB_DQS_DP<0>
  105  DQS0_B_C  BI  = M_B_CPU0_SB_DQS_DN<0>
  106  VSS46  POWER  = GND
  107  DQ4_B  BI  = M_B_CPU0_SB_DQ<4>
  108  VSS47  POWER  = GND
  109  DQ5_B  BI  = M_B_CPU0_SB_DQ<5>
  110  VSS48  POWER  = GND
  111  DQ8_B  BI  = M_B_CPU0_SB_DQ<8>
  112  VSS49  POWER  = GND
  113  DQ9_B  BI  = M_B_CPU0_SB_DQ<9>
  114  VSS50  POWER  = GND
  115  DQS1_B_T  BI  = M_B_CPU0_SB_DQS_DP<1>
  116  DQS1_B_C  BI  = M_B_CPU0_SB_DQS_DN<1>
  117  VSS51  POWER  = GND
  118  DQ12_B  BI  = M_B_CPU0_SB_DQ<12>
  119  VSS52  POWER  = GND
  120  DQ13_B  BI  = M_B_CPU0_SB_DQ<13>
  121  VSS53  POWER  = GND
  122  DQ16_B  BI  = M_B_CPU0_SB_DQ<16>
  123  VSS54  POWER  = GND
  124  DQ17_B  BI  = M_B_CPU0_SB_DQ<17>
  125  VSS55  POWER  = GND
  126  DQS2_B_T  BI  = M_B_CPU0_SB_DQS_DP<2>
  127  DQS2_B_C  BI  = M_B_CPU0_SB_DQS_DN<2>
  128  VSS56  POWER  = GND
  129  DQ20_B  BI  = M_B_CPU0_SB_DQ<20>
  130  VSS57  POWER  = GND
  131  DQ21_B  BI  = M_B_CPU0_SB_DQ<21>
  132  VSS58  POWER  = GND
  133  DQ24_B  BI  = M_B_CPU0_SB_DQ<24>
  134  VSS59  POWER  = GND
  135  DQ25_B  BI  = M_B_CPU0_SB_DQ<25>
  136  VSS60  POWER  = GND
  137  DQS3_B_T  BI  = M_B_CPU0_SB_DQS_DP<3>
  138  DQS3_B_C  BI  = M_B_CPU0_SB_DQS_DN<3>
  139  VSS61  POWER  = GND
  140  DQ28_B  BI  = M_B_CPU0_SB_DQ<28>
  141  VSS62  POWER  = GND
  142  DQ29_B  BI  = M_B_CPU0_SB_DQ<29>
  143  VSS63  POWER  = GND
  144  RFU1  TRI  = TP_CHB_CPU0_DIMM2_FRU_1
  145  VIN_BULK1  POWER  = P12V_S3_AUX_CPU0_NVDIMM
  146  VIN_BULK2  POWER  = P12V_S3_AUX_CPU0_NVDIMM
  147  \pwr_good||fail_n\  BI  = PWRGD_CHB_CPU0_DIMM2
  148  HSA  IN  = PD_CHB_CPU0_DIMM2_SAA
  149  RFU2  TRI  = TP_CHB_CPU0_DIMM2_FRU_2
  150  RFU3  TRI  = TP_CHB_CPU0_DIMM2_FRU_3
  151  VSS64  POWER  = GND
  152  DQ2_A  BI  = M_B_CPU0_SA_DQ<2>
  153  VSS65  POWER  = GND
  154  DQ3_A  BI  = M_B_CPU0_SA_DQ<3>
  155  VSS66  POWER  = GND
  156  \dqs5_a_c||tdqs5_a_c||dqs5_a_t||tdqs5_a_t\  BI  = M_B_CPU0_SA_DQS_DN<5>
  157  \dqs5_a_t||tdqs5_a_t\  BI  = M_B_CPU0_SA_DQS_DP<5>
  158  VSS67  POWER  = GND
  159  DQ6_A  BI  = M_B_CPU0_SA_DQ<6>
  160  VSS68  POWER  = GND
  161  DQ7_A  BI  = M_B_CPU0_SA_DQ<7>
  162  VSS69  POWER  = GND
  163  DQ10_A  BI  = M_B_CPU0_SA_DQ<10>
  164  VSS70  POWER  = GND
  165  DQ11_A  BI  = M_B_CPU0_SA_DQ<11>
  166  VSS71  POWER  = GND
  167  \dqs6_a_c||tdqs6_a_c||dqs6_a_t||tdqs6_a_t\  BI  = M_B_CPU0_SA_DQS_DN<6>
  168  \dqs6_a_t||tdqs6_a_t\  BI  = M_B_CPU0_SA_DQS_DP<6>
  169  VSS72  POWER  = GND
  170  DQ14_A  BI  = M_B_CPU0_SA_DQ<14>
  171  VSS73  POWER  = GND
  172  DQ15_A  BI  = M_B_CPU0_SA_DQ<15>
  173  VSS74  POWER  = GND
  174  DQ18_A  BI  = M_B_CPU0_SA_DQ<18>
  175  VSS75  POWER  = GND
  176  DQ19_A  BI  = M_B_CPU0_SA_DQ<19>
  177  VSS76  POWER  = GND
  178  \dqs7_a_c||tdqs7_a_c\  BI  = M_B_CPU0_SA_DQS_DN<7>
  179  \dqs7_a_t||tdqs7_a_t\  BI  = M_B_CPU0_SA_DQS_DP<7>
  180  VSS77  POWER  = GND
  181  DQ22_A  BI  = M_B_CPU0_SA_DQ<22>
  182  VSS78  POWER  = GND
  183  DQ23_A  BI  = M_B_CPU0_SA_DQ<23>
  184  VSS79  POWER  = GND
  185  DQ26_A  BI  = M_B_CPU0_SA_DQ<26>
  186  VSS80  POWER  = GND
  187  DQ27_A  BI  = M_B_CPU0_SA_DQ<27>
  188  VSS81  POWER  = GND
  189  \dqs8_a_c||tdqs8_a_c\  BI  = M_B_CPU0_SA_DQS_DN<8>
  190  \dqs8_a_t||tdqs8_a_t\  BI  = M_B_CPU0_SA_DQS_DP<8>
  191  VSS82  POWER  = GND
  192  DQ30_A  BI  = M_B_CPU0_SA_DQ<30>
  193  VSS83  POWER  = GND
  194  DQ31_A  BI  = M_B_CPU0_SA_DQ<31>
  195  VSS84  POWER  = GND
  196  CB2_A  BI  = M_B_CPU0_SA_CB<2>
  197  VSS85  POWER  = GND
  198  CB3_A  BI  = M_B_CPU0_SA_CB<3>
  199  VSS86  POWER  = GND
  200  \dqs9_a_c||tdqs9_a_c\  BI  = M_B_CPU0_SA_DQS_DN<9>
  201  \dqs9_a_t||tdqs9_a_t\  BI  = M_B_CPU0_SA_DQS_DP<9>
  202  VSS87  POWER  = GND
  203  CB6_A  BI  = M_B_CPU0_SA_CB<6>
  204  VSS88  POWER  = GND
  205  CB7_A  BI  = M_B_CPU0_SA_CB<7>
  206  VSS89  POWER  = GND
  207  RESET_N  IN  = RST_M_AB_CPU0_FPGA_N
  208  VSS90  POWER  = GND
  209  CS1_A_N  IN  = M_B_CPU0_SA_CS_N<3>
  210  VSS91  POWER  = GND
  211  CA1_A  IN  = M_B_CPU0_SA_CA<1>
  212  VSS92  POWER  = GND
  213  CA3_A  IN  = M_B_CPU0_SA_CA<3>
  214  VSS93  POWER  = GND
  215  CA5_A  IN  = M_B_CPU0_SA_CA<5>
  216  VSS94  POWER  = GND
  217  CK_T  IN  = M_B_CPU0_CLK_DP<1>
  218  CK_C  IN  = M_B_CPU0_CLK_DN<1>
  219  VSS95  POWER  = GND
  220  RFU4  TRI  = TP_CHB_CPU0_DIMM2_FRU_4
  221  CA1_B  IN  = M_B_CPU0_SB_CA<1>
  222  VSS96  POWER  = GND
  223  CA3_B  IN  = M_B_CPU0_SB_CA<3>
  224  VSS97  POWER  = GND
  225  CA5_B  IN  = M_B_CPU0_SB_CA<5>
  226  VSS98  POWER  = GND
  227  PAR_B  IN  = M_B_CPU0_SB_PAR
  228  VSS99  POWER  = GND
  229  CS1_B_N  IN  = M_B_CPU0_SB_CS_N<3>
  230  VSS100  POWER  = GND
  231  RFU5  TRI  = TP_CHB_CPU0_DIMM2_FRU_5
  232  RFU6  TRI  = TP_CHB_CPU0_DIMM2_FRU_6
  233  VSS101  POWER  = GND
  234  CB6_B  BI  = M_B_CPU0_SB_CB<6>
  235  VSS102  POWER  = GND
  236  CB7_B  BI  = M_B_CPU0_SB_CB<7>
  237  VSS103  POWER  = GND
  238  DQS4_B_C  BI  = M_B_CPU0_SB_DQS_DN<4>
  239  DQS4_B_T  BI  = M_B_CPU0_SB_DQS_DP<4>
  240  VSS104  POWER  = GND
  241  CB2_B  BI  = M_B_CPU0_SB_CB<2>
  242  VSS105  POWER  = GND
  243  CB3_B  BI  = M_B_CPU0_SB_CB<3>
  244  VSS106  POWER  = GND
  245  DQ2_B  BI  = M_B_CPU0_SB_DQ<2>
  246  VSS107  POWER  = GND
  247  DQ3_B  BI  = M_B_CPU0_SB_DQ<3>
  248  VSS108  POWER  = GND
  249  \dqs5_b_c||tdqs5_b_c\  BI  = M_B_CPU0_SB_DQS_DN<5>
  250  \dqs5_b_t||tdqs5_b_t\  BI  = M_B_CPU0_SB_DQS_DP<5>
  251  VSS109  POWER  = GND
  252  DQ6_B  BI  = M_B_CPU0_SB_DQ<6>
  253  VSS110  POWER  = GND
  254  DQ7_B  BI  = M_B_CPU0_SB_DQ<7>
  255  VSS111  POWER  = GND
  256  DQ10_B  BI  = M_B_CPU0_SB_DQ<10>
  257  VSS112  POWER  = GND
  258  DQ11_B  BI  = M_B_CPU0_SB_DQ<11>
  259  VSS113  POWER  = GND
  260  \dqs6_b_c||tdqs6_b_c\  BI  = M_B_CPU0_SB_DQS_DN<6>
  261  \dqs6_b_t||tdqs6_b_t\  BI  = M_B_CPU0_SB_DQS_DP<6>
  262  VSS114  POWER  = GND
  263  DQ14_B  BI  = M_B_CPU0_SB_DQ<14>
  264  VSS115  POWER  = GND
  265  DQ15_B  BI  = M_B_CPU0_SB_DQ<15>
  266  VSS116  POWER  = GND
  267  DQ18_B  BI  = M_B_CPU0_SB_DQ<18>
  268  VSS117  POWER  = GND
  269  DQ19_B  BI  = M_B_CPU0_SB_DQ<19>
  270  VSS118  POWER  = GND
  271  \dqs7_b_c||tdqs7_b_c\  BI  = M_B_CPU0_SB_DQS_DN<7>
  272  \dqs7_b_t||tdqs7_b_t\  BI  = M_B_CPU0_SB_DQS_DP<7>
  273  VSS119  POWER  = GND
  274  DQ22_B  BI  = M_B_CPU0_SB_DQ<22>
  275  VSS120  POWER  = GND
  276  DQ23_B  BI  = M_B_CPU0_SB_DQ<23>
  277  VSS121  POWER  = GND
  278  DQ26_B  BI  = M_B_CPU0_SB_DQ<26>
  279  VSS122  POWER  = GND
  280  DQ27_B  BI  = M_B_CPU0_SB_DQ<27>
  281  VSS123  POWER  = GND
  282  \dqs8_b_c||tdqs8_b_c\  BI  = M_B_CPU0_SB_DQS_DN<8>
  283  \dqs8_b_t||tdqs8_b_t\  BI  = M_B_CPU0_SB_DQS_DP<8>
  284  VSS124  POWER  = GND
  285  DQ30_B  BI  = M_B_CPU0_SB_DQ<30>
  286  VSS125  POWER  = GND
  287  DQ31_B  BI  = M_B_CPU0_SB_DQ<31>
  288  VSS126  POWER  = GND
  G1  G1  POWER  = GND
  G2  G2  POWER  = GND
  G3  G3  POWER  = GND
